# BASEBOARD_FAB2 (Tioga Pass) — schematic netlist excerpt (pin names and nets, part order shuffled) for the footprints in the layout excerpt that follows; sources: Cadence DE-HDL packaged netlist, KiCad conversion of Wiwynn_Tioga_Pass_MB.brd

J9L2  SCONN288_H44441003  SCONN  pkg PIP  page 86
  \12v\(1)  = P12V_NVDIMM_KLM
  VSS(93)  = GND
  DQ(4)  = M_L_DQ<4>
  VSS(92)  = GND
  DQ(0)  = M_L_DQ<0>
  VSS(91)  = GND
  DQS9P  = M_L_DQS_DP<9>
  DQS9N  = M_L_DQS_DN<9>
  VSS(90)  = GND
  DQ(6)  = M_L_DQ<6>
  VSS(89)  = GND
  DQ(2)  = M_L_DQ<2>
  VSS(88)  = GND
  DQ(12)  = M_L_DQ<12>
  VSS(87)  = GND
  DQ(8)  = M_L_DQ<8>
  VSS(86)  = GND
  DQS10P  = M_L_DQS_DP<10>
  DQS10N  = M_L_DQS_DN<10>
  VSS(85)  = GND
  DQ(14)  = M_L_DQ<14>
  VSS(84)  = GND
  DQ(10)  = M_L_DQ<10>
  VSS(83)  = GND
  DQ(20)  = M_L_DQ<20>
  VSS(82)  = GND
  DQ(16)  = M_L_DQ<16>
  VSS(81)  = GND
  DQS11P  = M_L_DQS_DP<11>
  DQS11N  = M_L_DQS_DN<11>
  VSS(80)  = GND
  DQ(22)  = M_L_DQ<22>
  VSS(79)  = GND
  DQ(18)  = M_L_DQ<18>
  VSS(78)  = GND
  DQ(28)  = M_L_DQ<28>
  VSS(77)  = GND
  DQ(24)  = M_L_DQ<24>
  VSS(76)  = GND
  DQS12P  = M_L_DQS_DP<12>
  DQS12N  = M_L_DQS_DN<12>
  VSS(75)  = GND
  DQ(30)  = M_L_DQ<30>
  VSS(74)  = GND
  DQ(26)  = M_L_DQ<26>
  VSS(73)  = GND
  CB(4)  = M_L_ECC<4>
  VSS(72)  = GND
  CB(0)  = M_L_ECC<0>
  VSS(71)  = GND
  DQS17P  = M_L_DQS_DP<17>
  DQS17N  = M_L_DQS_DN<17>
  VSS(70)  = GND
  CB(6)  = M_L_ECC<6>
  VSS(69)  = GND
  CB(2)  = M_L_ECC<2>
  VSS(68)  = GND
  RESET_N  = M_KLM_RST_N
  VDD(25)  = PVDDQ_KLM
  CKE(0)  = M_L_CKE<2>
  VDD(24)  = PVDDQ_KLM
  ACT_N  = M_L_ACT_N
  BG(0)  = M_L_BG<0>
  VDD(23)  = PVDDQ_KLM
  A12  = M_L_MA<12>
  A9  = M_L_MA<9>
  VDD(22)  = PVDDQ_KLM
  A8  = M_L_MA<8>
  A6  = M_L_MA<6>
  VDD(21)  = PVDDQ_KLM
  A3  = M_L_MA<3>
  A1  = M_L_MA<1>
  VDD(20)  = PVDDQ_KLM
  CK0P  = M_L_CLK_DP<2>
  CK0N  = M_L_CLK_DN<2>
  VDD(19)  = PVDDQ_KLM
  VTT(1)  = PVTT_KLM
  EVENT_N  = FM_DIMM_EVENT_COD_N
  A0  = M_L_MA<0>
  VDD(18)  = PVDDQ_KLM
  BA(0)  = M_L_BA<0>
  A16_RAS_N  = M_L_MA<16>
  VDD(17)  = PVDDQ_KLM
  S0_N  = M_L_CS_N<4>
  VDD(16)  = PVDDQ_KLM
  A15_CAS_N  = M_L_MA<15>
  ODT(0)  = M_L_ODT<2>
  VDD(15)  = PVDDQ_KLM
  S1_N  = M_L_CS_N<5>
  VDD(14)  = PVDDQ_KLM
  ODT(1)  = M_L_ODT<3>
  VDD(13)  = PVDDQ_KLM
  S2_N_C(0)  = M_L_CS_N<6>
  VSS(67)  = GND
  DQ(36)  = M_L_DQ<36>
  VSS(66)  = GND
  DQ(32)  = M_L_DQ<32>
  VSS(65)  = GND
  DQS13P  = M_L_DQS_DP<13>
  DQS13N  = M_L_DQS_DN<13>
  VSS(64)  = GND
  DQ(38)  = M_L_DQ<38>
  VSS(63)  = GND
  DQ(34)  = M_L_DQ<34>
  VSS(62)  = GND
  DQ(44)  = M_L_DQ<44>
  VSS(61)  = GND
  DQ(40)  = M_L_DQ<40>
  VSS(60)  = GND
  DQS14P  = M_L_DQS_DP<14>
  DQS14N  = M_L_DQS_DN<14>
  VSS(59)  = GND
  DQ(46)  = M_L_DQ<46>
  VSS(58)  = GND
  DQ(42)  = M_L_DQ<42>
  VSS(57)  = GND
  DQ(52)  = M_L_DQ<52>
  VSS(56)  = GND
  DQ(48)  = M_L_DQ<48>
  VSS(55)  = GND
  DQS15P  = M_L_DQS_DP<15>
  DQS15N  = M_L_DQS_DN<15>
  VSS(54)  = GND
  DQ(54)  = M_L_DQ<54>
  VSS(53)  = GND
  DQ(50)  = M_L_DQ<50>
  VSS(52)  = GND
  DQ(60)  = M_L_DQ<60>
  VSS(51)  = GND
  DQ(56)  = M_L_DQ<56>
  VSS(50)  = GND
  DQS16P  = M_L_DQS_DP<16>
  DQS16N  = M_L_DQS_DN<16>
  VSS(49)  = GND
  DQ(62)  = M_L_DQ<62>
  VSS(48)  = GND
  DQ(58)  = M_L_DQ<58>
  VSS(47)  = GND
  SA(0)  = PVPP_KLM
  SA(1)  = PVPP_KLM
  SCL  = SMB_DDR_KLM_VPP_SCL
  VPP(4)  = PVPP_KLM
  VPP(3)  = PVPP_KLM
  RFU(2)  = TP_CH_L_DIMM0_RFU_2
  \12v\(0)  = P12V_NVDIMM_KLM
  VREFCA  = M_L_VREF
  VSS(46)  = GND
  DQ(5)  = M_L_DQ<5>
  VSS(45)  = GND
  DQ(1)  = M_L_DQ<1>
  VSS(44)  = GND
  DQS0N  = M_L_DQS_DN<0>
  DQS0P  = M_L_DQS_DP<0>
  VSS(43)  = GND
  DQ(7)  = M_L_DQ<7>
  VSS(42)  = GND
  DQ(3)  = M_L_DQ<3>
  VSS(41)  = GND
  DQ(13)  = M_L_DQ<13>
  VSS(40)  = GND
  DQ(9)  = M_L_DQ<9>
  VSS(39)  = GND
  DQS1N  = M_L_DQS_DN<1>
  DQS1P  = M_L_DQS_DP<1>
  VSS(38)  = GND
  DQ(15)  = M_L_DQ<15>
  VSS(37)  = GND
  DQ(11)  = M_L_DQ<11>
  VSS(36)  = GND
  DQ(21)  = M_L_DQ<21>
  VSS(35)  = GND
  DQ(17)  = M_L_DQ<17>
  VSS(34)  = GND
  DQS2N  = M_L_DQS_DN<2>
  DQS2P  = M_L_DQS_DP<2>
  VSS(33)  = GND
  DQ(23)  = M_L_DQ<23>
  VSS(32)  = GND
  DQ(19)  = M_L_DQ<19>
  VSS(31)  = GND
  DQ(29)  = M_L_DQ<29>
  VSS(30)  = GND
  DQ(25)  = M_L_DQ<25>
  VSS(29)  = GND
  DQS3N  = M_L_DQS_DN<3>
  DQS3P  = M_L_DQS_DP<3>
  VSS(28)  = GND
  DQ(31)  = M_L_DQ<31>
  VSS(27)  = GND
  DQ(27)  = M_L_DQ<27>
  VSS(26)  = GND
  CB(5)  = M_L_ECC<5>
  VSS(25)  = GND
  CB(1)  = M_L_ECC<1>
  VSS(24)  = GND
  DQS8N  = M_L_DQS_DN<8>
  DQS8P  = M_L_DQS_DP<8>
  VSS(23)  = GND
  CB(7)  = M_L_ECC<7>
  VSS(22)  = GND
  CB(3)  = M_L_ECC<3>
  VSS(21)  = GND
  CKE(1)  = M_L_CKE<3>
  VDD(12)  = PVDDQ_KLM
  RFU(0)  = TP_CH_L_DIMM0_RFU_0
  VDD(11)  = PVDDQ_KLM
  BG(1)  = M_L_BG<1>
  ALERT_N  = M_L_ALERT_N
  VDD(10)  = PVDDQ_KLM
  A11  = M_L_MA<11>
  A7  = M_L_MA<7>
  VDD(9)  = PVDDQ_KLM
  A5  = M_L_MA<5>
  A4  = M_L_MA<4>
  VDD(8)  = PVDDQ_KLM
  A2  = M_L_MA<2>
  VDD(7)  = PVDDQ_KLM
  CK1P  = M_L_CLK_DP<3>
  CK1N  = M_L_CLK_DN<3>
  VDD(6)  = PVDDQ_KLM
  VTT(0)  = PVTT_KLM
  PAR  = M_L_PAR
  VDD(5)  = PVDDQ_KLM
  BA(1)  = M_L_BA<1>
  A10  = M_L_MA<10>
  VDD(4)  = PVDDQ_KLM
  RFU(1)  = TP_CH_L_DIMM0_RFU_1
  A14_WE_N  = M_L_MA<14>
  VDD(3)  = PVDDQ_KLM
  SAVE_N_NC  = FM_ADR_COMPLETE_KLM_N
  VDD(2)  = PVDDQ_KLM
  A13  = M_L_MA<13>
  VDD(1)  = PVDDQ_KLM
  A17  = M_L_MA<17>
  C(2)  = M_L_C<2>
  VDD(0)  = PVDDQ_KLM
  S3_N_C(1)  = M_L_CS_N<7>
  SA(2)  = GND
  VSS(20)  = GND
  DQ(37)  = M_L_DQ<37>
  VSS(19)  = GND
  DQ(33)  = M_L_DQ<33>
  VSS(18)  = GND
  DQS4N  = M_L_DQS_DN<4>
  DQS4P  = M_L_DQS_DP<4>
  VSS(17)  = GND
  DQ(39)  = M_L_DQ<39>
  VSS(16)  = GND
  DQ(35)  = M_L_DQ<35>
  VSS(15)  = GND
  DQ(45)  = M_L_DQ<45>
  VSS(14)  = GND
  DQ(41)  = M_L_DQ<41>
  VSS(13)  = GND
  DQS5N  = M_L_DQS_DN<5>
  DQS5P  = M_L_DQS_DP<5>
  VSS(12)  = GND
  DQ(47)  = M_L_DQ<47>
  VSS(11)  = GND
  DQ(43)  = M_L_DQ<43>
  VSS(10)  = GND
  DQ(53)  = M_L_DQ<53>
  VSS(9)  = GND
  DQ(49)  = M_L_DQ<49>
  VSS(8)  = GND
  DQS6N  = M_L_DQS_DN<6>
  DQS6P  = M_L_DQS_DP<6>
  VSS(7)  = GND
  DQ(55)  = M_L_DQ<55>
  VSS(6)  = GND
  DQ(51)  = M_L_DQ<51>
  VSS(5)  = GND
  DQ(61)  = M_L_DQ<61>
  VSS(4)  = GND
  DQ(57)  = M_L_DQ<57>
  VSS(3)  = GND
  DQS7N  = M_L_DQS_DN<7>
  DQS7P  = M_L_DQS_DP<7>
  VSS(2)  = GND
  DQ(63)  = M_L_DQ<63>
  VSS(1)  = GND
  DQ(59)  = M_L_DQ<59>
  VSS(0)  = GND
  VDDSPD  = PVPP_KLM
  SDA  = SMB_DDR_KLM_VPP_SDA
  VPP(1)  = PVPP_KLM
  VPP(0)  = PVPP_KLM
  VPP(2)  = PVPP_KLM

(kicad_pcb
	(version 20260206)
	(generator "pcbnew")
	(generator_version "10.0")
	(general
		(thickness 1.6)
		(legacy_teardrops no)
	)
	(paper "A4")
	(title_block
		(title "Wiwynn_Tioga_Pass_MB.brd")
		(comment 1 "Tioga Pass / footprint 4281 of 4770 (J9L2), pads 152-201 of 291")
	)
	(layers
		(0 "F.Cu" signal "TOP")
		(4 "In1.Cu" signal "L2GND")
		(6 "In2.Cu" signal "L3")
		(8 "In3.Cu" signal "L4GND")
		(10 "In4.Cu" signal "L5")
		(12 "In5.Cu" signal "L6GND")
		(14 "In6.Cu" signal "L7VCC")
		(16 "In7.Cu" signal "L8VCC")
		(18 "In8.Cu" signal "L9GND")
		(20 "In9.Cu" signal "L10")
		(22 "In10.Cu" signal "L11GND")
		(24 "In11.Cu" signal "L12")
		(26 "In12.Cu" signal "L13GND")
		(2 "B.Cu" signal "BOTTOM")
		(9 "F.Adhes" user "F.Adhesive")
		(11 "B.Adhes" user "B.Adhesive")
		(13 "F.Paste" user "Package Geometry/Pastemask Top")
		(15 "B.Paste" user "Package Geometry/Pastemask Bottom")
		(5 "F.SilkS" user "Ref Des/Silkscreen Top")
		(7 "B.SilkS" user "Ref Des/Silkscreen Bottom")
		(1 "F.Mask" user "Board Geometry/Soldermask Top")
		(3 "B.Mask" user "Board Geometry/Soldermask Bottom")
		(17 "Dwgs.User" user "User.Drawings")
		(19 "Cmts.User" user "User.Comments")
		(21 "Eco1.User" user "User.Eco1")
		(23 "Eco2.User" user "User.Eco2")
		(25 "Edge.Cuts" user "Board Geometry/Outline")
		(27 "Margin" user)
		(31 "F.CrtYd" user "Package Geometry/Place Bound Top")
		(29 "B.CrtYd" user "Package Geometry/Place Bound Bottom")
		(35 "F.Fab" user "Ref Des/Assembly Top")
		(33 "B.Fab" user "Ref Des/Assembly Bottom")
	)
	(footprint ""
		(layer "B.Cu")
		(at 29.699458 -142.477236 90)
		(property "Reference" "J9L2"
			(at 2.403348 38.118542 0)
			(unlocked yes)
			(layer "B.SilkS")
			(effects
				(font
					(size 0.7874 0.5842)
					(thickness 0.1524)
				)
				(justify left mirror)
			)
		)
		(property "Value" ""
			(at 0 0 90)
			(layer "B.Fab")
			(effects
				(font
					(size 1.27 1.27)
				)
				(justify mirror)
			)
		)
		(duplicate_pad_numbers_are_jumpers no)
		(pad "149" smd rect
			(at -4.59994 3.400044 270)
			(size 1.8034 0.508)
			(layers "B.Cu" "B.Mask" "B.Paste")
			(net "GND")
		)
		(pad "150" smd rect
			(at -4.59994 4.249928 270)
			(size 1.8034 0.508)
			(layers "B.Cu" "B.Mask" "B.Paste")
			(net "M_L_DQ<1>")
		)
		(pad "151" smd rect
			(at -4.59994 5.100066 270)
			(size 1.8034 0.508)
			(layers "B.Cu" "B.Mask" "B.Paste")
			(net "GND")
		)
		(pad "152" smd rect
			(at -4.59994 5.94995 270)
			(size 1.8034 0.508)
			(layers "B.Cu" "B.Mask" "B.Paste")
			(net "M_L_DQS_DN<0>")
		)
		(pad "153" smd rect
			(at -4.59994 6.800088 270)
			(size 1.8034 0.508)
			(layers "B.Cu" "B.Mask" "B.Paste")
			(net "M_L_DQS_DP<0>")
		)
		(pad "154" smd rect
			(at -4.59994 7.649972 270)
			(size 1.8034 0.508)
			(layers "B.Cu" "B.Mask" "B.Paste")
			(net "GND")
		)
		(pad "155" smd rect
			(at -4.59994 8.50011 270)
			(size 1.8034 0.508)
			(layers "B.Cu" "B.Mask" "B.Paste")
			(net "M_L_DQ<7>")
		)
		(pad "156" smd rect
			(at -4.59994 9.349994 270)
			(size 1.8034 0.508)
			(layers "B.Cu" "B.Mask" "B.Paste")
			(net "GND")
		)
		(pad "157" smd rect
			(at -4.59994 10.199878 270)
			(size 1.8034 0.508)
			(layers "B.Cu" "B.Mask" "B.Paste")
			(net "M_L_DQ<3>")
		)
		(pad "158" smd rect
			(at -4.59994 11.050016 270)
			(size 1.8034 0.508)
			(layers "B.Cu" "B.Mask" "B.Paste")
			(net "GND")
		)
		(pad "159" smd rect
			(at -4.59994 11.8999 270)
			(size 1.8034 0.508)
			(layers "B.Cu" "B.Mask" "B.Paste")
			(net "M_L_DQ<13>")
		)
		(pad "160" smd rect
			(at -4.59994 12.750038 270)
			(size 1.8034 0.508)
			(layers "B.Cu" "B.Mask" "B.Paste")
			(net "GND")
		)
		(pad "161" smd rect
			(at -4.59994 13.599922 270)
			(size 1.8034 0.508)
			(layers "B.Cu" "B.Mask" "B.Paste")
			(net "M_L_DQ<9>")
		)
		(pad "162" smd rect
			(at -4.59994 14.45006 270)
			(size 1.8034 0.508)
			(layers "B.Cu" "B.Mask" "B.Paste")
			(net "GND")
		)
		(pad "163" smd rect
			(at -4.59994 15.299944 270)
			(size 1.8034 0.508)
			(layers "B.Cu" "B.Mask" "B.Paste")
			(net "M_L_DQS_DN<1>")
		)
		(pad "164" smd rect
			(at -4.59994 16.150082 270)
			(size 1.8034 0.508)
			(layers "B.Cu" "B.Mask" "B.Paste")
			(net "M_L_DQS_DP<1>")
		)
		(pad "165" smd rect
			(at -4.59994 16.999966 270)
			(size 1.8034 0.508)
			(layers "B.Cu" "B.Mask" "B.Paste")
			(net "GND")
		)
		(pad "166" smd rect
			(at -4.59994 17.850104 270)
			(size 1.8034 0.508)
			(layers "B.Cu" "B.Mask" "B.Paste")
			(net "M_L_DQ<15>")
		)
		(pad "167" smd rect
			(at -4.59994 18.699988 270)
			(size 1.8034 0.508)
			(layers "B.Cu" "B.Mask" "B.Paste")
			(net "GND")
		)
		(pad "168" smd rect
			(at -4.59994 19.550126 270)
			(size 1.8034 0.508)
			(layers "B.Cu" "B.Mask" "B.Paste")
			(net "M_L_DQ<11>")
		)
		(pad "169" smd rect
			(at -4.59994 20.40001 270)
			(size 1.8034 0.508)
			(layers "B.Cu" "B.Mask" "B.Paste")
			(net "GND")
		)
		(pad "170" smd rect
			(at -4.59994 21.249894 270)
			(size 1.8034 0.508)
			(layers "B.Cu" "B.Mask" "B.Paste")
			(net "M_L_DQ<21>")
		)
		(pad "171" smd rect
			(at -4.59994 22.100032 270)
			(size 1.8034 0.508)
			(layers "B.Cu" "B.Mask" "B.Paste")
			(net "GND")
		)
		(pad "172" smd rect
			(at -4.59994 22.949916 270)
			(size 1.8034 0.508)
			(layers "B.Cu" "B.Mask" "B.Paste")
			(net "M_L_DQ<17>")
		)
		(pad "173" smd rect
			(at -4.59994 23.800054 270)
			(size 1.8034 0.508)
			(layers "B.Cu" "B.Mask" "B.Paste")
			(net "GND")
		)
		(pad "174" smd rect
			(at -4.59994 24.649938 270)
			(size 1.8034 0.508)
			(layers "B.Cu" "B.Mask" "B.Paste")
			(net "M_L_DQS_DN<2>")
		)
		(pad "175" smd rect
			(at -4.59994 25.500076 270)
			(size 1.8034 0.508)
			(layers "B.Cu" "B.Mask" "B.Paste")
			(net "M_L_DQS_DP<2>")
		)
		(pad "176" smd rect
			(at -4.59994 26.34996 270)
			(size 1.8034 0.508)
			(layers "B.Cu" "B.Mask" "B.Paste")
			(net "GND")
		)
		(pad "177" smd rect
			(at -4.59994 27.200098 270)
			(size 1.8034 0.508)
			(layers "B.Cu" "B.Mask" "B.Paste")
			(net "M_L_DQ<23>")
		)
		(pad "178" smd rect
			(at -4.59994 28.049982 270)
			(size 1.8034 0.508)
			(layers "B.Cu" "B.Mask" "B.Paste")
			(net "GND")
		)
		(pad "179" smd rect
			(at -4.59994 28.90012 270)
			(size 1.8034 0.508)
			(layers "B.Cu" "B.Mask" "B.Paste")
			(net "M_L_DQ<19>")
		)
		(pad "180" smd rect
			(at -4.59994 29.750004 270)
			(size 1.8034 0.508)
			(layers "B.Cu" "B.Mask" "B.Paste")
			(net "GND")
		)
		(pad "181" smd rect
			(at -4.59994 30.599888 270)
			(size 1.8034 0.508)
			(layers "B.Cu" "B.Mask" "B.Paste")
			(net "M_L_DQ<29>")
		)
		(pad "182" smd rect
			(at -4.59994 31.450026 270)
			(size 1.8034 0.508)
			(layers "B.Cu" "B.Mask" "B.Paste")
			(net "GND")
		)
		(pad "183" smd rect
			(at -4.59994 32.29991 270)
			(size 1.8034 0.508)
			(layers "B.Cu" "B.Mask" "B.Paste")
			(net "M_L_DQ<25>")
		)
		(pad "184" smd rect
			(at -4.59994 33.150048 270)
			(size 1.8034 0.508)
			(layers "B.Cu" "B.Mask" "B.Paste")
			(net "GND")
		)
		(pad "185" smd rect
			(at -4.59994 33.999932 270)
			(size 1.8034 0.508)
			(layers "B.Cu" "B.Mask" "B.Paste")
			(net "M_L_DQS_DN<3>")
		)
		(pad "186" smd rect
			(at -4.59994 34.85007 270)
			(size 1.8034 0.508)
			(layers "B.Cu" "B.Mask" "B.Paste")
			(net "M_L_DQS_DP<3>")
		)
		(pad "187" smd rect
			(at -4.59994 35.699954 270)
			(size 1.8034 0.508)
			(layers "B.Cu" "B.Mask" "B.Paste")
			(net "GND")
		)
		(pad "188" smd rect
			(at -4.59994 36.550092 270)
			(size 1.8034 0.508)
			(layers "B.Cu" "B.Mask" "B.Paste")
			(net "M_L_DQ<31>")
		)
		(pad "189" smd rect
			(at -4.59994 37.399976 270)
			(size 1.8034 0.508)
			(layers "B.Cu" "B.Mask" "B.Paste")
			(net "GND")
		)
		(pad "190" smd rect
			(at -4.59994 38.250114 270)
			(size 1.8034 0.508)
			(layers "B.Cu" "B.Mask" "B.Paste")
			(net "M_L_DQ<27>")
		)
		(pad "191" smd rect
			(at -4.59994 39.099998 270)
			(size 1.8034 0.508)
			(layers "B.Cu" "B.Mask" "B.Paste")
			(net "GND")
		)
		(pad "192" smd rect
			(at -4.59994 39.949882 270)
			(size 1.8034 0.508)
			(layers "B.Cu" "B.Mask" "B.Paste")
			(net "M_L_ECC<5>")
		)
		(pad "193" smd rect
			(at -4.59994 40.80002 270)
			(size 1.8034 0.508)
			(layers "B.Cu" "B.Mask" "B.Paste")
			(net "GND")
		)
		(pad "194" smd rect
			(at -4.59994 41.649904 270)
			(size 1.8034 0.508)
			(layers "B.Cu" "B.Mask" "B.Paste")
			(net "M_L_ECC<1>")
		)
		(pad "195" smd rect
			(at -4.59994 42.500042 270)
			(size 1.8034 0.508)
			(layers "B.Cu" "B.Mask" "B.Paste")
			(net "GND")
		)
		(pad "196" smd rect
			(at -4.59994 43.349926 270)
			(size 1.8034 0.508)
			(layers "B.Cu" "B.Mask" "B.Paste")
			(net "M_L_DQS_DN<8>")
		)
		(pad "197" smd rect
			(at -4.59994 44.200064 270)
			(size 1.8034 0.508)
			(layers "B.Cu" "B.Mask" "B.Paste")
			(net "M_L_DQS_DP<8>")
		)
		(pad "198" smd rect
			(at -4.59994 45.049948 270)
			(size 1.8034 0.508)
			(layers "B.Cu" "B.Mask" "B.Paste")
			(net "GND")
		)
	)
)
